(kicad_pcb
	(version 20260206)
	(generator "pcbnew")
	(generator_version "10.0")
	(general
		(thickness 1.6)
		(legacy_teardrops no)
	)
	(paper "A4")
	(title_block
		(title "baseboard — 13948-1b.1110WZS1818.brd")
		(comment 1 "Honey Badger (Wiwynn) / footprints 94-101 of 2523")
	)
	(layers
		(0 "F.Cu" signal "TOP")
		(4 "In1.Cu" signal "L2GND")
		(6 "In2.Cu" signal "L3")
		(8 "In3.Cu" signal "L4VCC")
		(10 "In4.Cu" signal "L5VCC")
		(12 "In5.Cu" signal "L6")
		(14 "In6.Cu" signal "L7GND")
		(2 "B.Cu" signal "BOTTOM")
		(9 "F.Adhes" user "F.Adhesive")
		(11 "B.Adhes" user "B.Adhesive")
		(13 "F.Paste" user "Package Geometry/Pastemask Top")
		(15 "B.Paste" user "Package Geometry/Pastemask Bottom")
		(5 "F.SilkS" user "Ref Des/Silkscreen Top")
		(7 "B.SilkS" user "Ref Des/Silkscreen Bottom")
		(1 "F.Mask" user "Board Geometry/Soldermask Top")
		(3 "B.Mask" user "Board Geometry/Soldermask Bottom")
		(17 "Dwgs.User" user "User.Drawings")
		(19 "Cmts.User" user "User.Comments")
		(21 "Eco1.User" user "User.Eco1")
		(23 "Eco2.User" user "User.Eco2")
		(25 "Edge.Cuts" user "Board Geometry/Outline")
		(27 "Margin" user)
		(31 "F.CrtYd" user "Package Geometry/Place Bound Top")
		(29 "B.CrtYd" user "Package Geometry/Place Bound Bottom")
		(35 "F.Fab" user "Ref Des/Assembly Top")
		(33 "B.Fab" user "Ref Des/Assembly Bottom")
	)
	(footprint ""
		(layer "F.Cu")
		(at 93.072966 -60.452)
		(property "Reference" "STP35"
			(at 0 0 0)
			(layer "F.SilkS")
			(hide yes)
			(effects
				(font
					(size 1.27 1.27)
				)
			)
		)
		(property "Value" "TPAD28"
			(at 0.0127 -1.8034 0)
			(unlocked yes)
			(layer "F.Fab")
			(hide yes)
			(effects
				(font
					(size 1.016 1.016)
					(thickness 0.1524)
				)
			)
		)
		(property "Device Type" "TPAD28"
			(at 0.0127 -3.3274 0)
			(unlocked yes)
			(layer "F.Fab")
			(hide yes)
			(effects
				(font
					(size 1.016 1.016)
					(thickness 0.1524)
				)
			)
		)
		(duplicate_pad_numbers_are_jumpers no)
		(fp_poly
			(pts
				(arc
					(start 0.3556 0)
					(mid -0.3556 0)
					(end 0.3556 0)
				)
			)
			(stroke
				(width 0)
				(type default)
			)
			(fill no)
			(layer "F.CrtYd")
		)
		(fp_poly
			(pts
				(arc
					(start 0.6096 0)
					(mid -0.6096 0)
					(end 0.6096 0)
				)
			)
			(stroke
				(width 0)
				(type default)
			)
			(fill no)
			(layer "F.Fab")
		)
		(pad "1" smd circle
			(at 0 0)
			(size 0.7112 0.7112)
			(layers "F.Cu" "F.Mask" "F.Paste")
			(net "ICE1_TCK")
		)
	)
	(footprint ""
		(layer "F.Cu")
		(at 106.788966 -65.8876 180)
		(property "Reference" "SR866"
			(at 0 0 180)
			(layer "F.SilkS")
			(hide yes)
			(effects
				(font
					(size 1.27 1.27)
				)
			)
		)
		(property "Value" "0R2J-2-GP"
			(at 0.064008 -3.993896 180)
			(unlocked yes)
			(layer "F.Fab")
			(hide yes)
			(effects
				(font
					(size 1.016 1.016)
					(thickness 0.1524)
				)
			)
		)
		(property "Device Type" "R402H16"
			(at 0.064008 -5.517896 180)
			(unlocked yes)
			(layer "F.Fab")
			(hide yes)
			(effects
				(font
					(size 1.016 1.016)
					(thickness 0.1524)
				)
			)
		)
		(duplicate_pad_numbers_are_jumpers no)
		(fp_line
			(start 0.508 -0.9398)
			(end -0.508 -0.9398)
			(stroke
				(width 0.1524)
				(type default)
			)
			(layer "F.SilkS")
		)
		(fp_line
			(start -0.508 -0.9398)
			(end -0.508 0.9398)
			(stroke
				(width 0.1524)
				(type default)
			)
			(layer "F.SilkS")
		)
		(fp_rect
			(start -0.508 0.9398)
			(end 0.508 -0.9398)
			(stroke
				(width 0)
				(type default)
			)
			(fill no)
			(layer "F.CrtYd")
		)
		(fp_rect
			(start -0.508 0.9398)
			(end 0.508 -0.9398)
			(stroke
				(width 0)
				(type default)
			)
			(fill no)
			(layer "F.Fab")
		)
		(pad "1" smd custom
			(at 0 -0.4445 180)
			(size 0.1397 0.1397)
			(layers "F.Cu" "F.Mask" "F.Paste")
			(net "IOC_TRST_N")
			(options
				(clearance outline)
				(anchor circle)
			)
			(primitives
				(gr_poly
					(pts
						(arc
							(start -0.1778 -0.2794)
							(mid -0.249642 -0.249642)
							(end -0.2794 -0.1778)
						)
						(arc
							(start -0.2794 0.1778)
							(mid -0.249642 0.249642)
							(end -0.1778 0.2794)
						)
						(arc
							(start 0.1778 0.2794)
							(mid 0.249642 0.249642)
							(end 0.2794 0.1778)
						)
						(arc
							(start 0.2794 -0.1778)
							(mid 0.249642 -0.249642)
							(end 0.1778 -0.2794)
						)
					)
					(width 0)
					(fill yes)
				)
			)
		)
		(pad "2" smd custom
			(at 0 0.4445 180)
			(size 0.1397 0.1397)
			(layers "F.Cu" "F.Mask" "F.Paste")
			(net "JTAG_EXP_IOC_RST")
			(options
				(clearance outline)
				(anchor circle)
			)
			(primitives
				(gr_poly
					(pts
						(arc
							(start -0.1778 -0.2794)
							(mid -0.249642 -0.249642)
							(end -0.2794 -0.1778)
						)
						(arc
							(start -0.2794 0.1778)
							(mid -0.249642 0.249642)
							(end -0.1778 0.2794)
						)
						(arc
							(start 0.1778 0.2794)
							(mid 0.249642 0.249642)
							(end 0.2794 0.1778)
						)
						(arc
							(start 0.2794 -0.1778)
							(mid 0.249642 -0.249642)
							(end 0.1778 -0.2794)
						)
					)
					(width 0)
					(fill yes)
				)
			)
		)
	)
	(footprint ""
		(layer "F.Cu")
		(at 200.856596 -110.255812 90)
		(property "Reference" "PC229"
			(at 0 0 90)
			(layer "F.SilkS")
			(hide yes)
			(effects
				(font
					(size 1.27 1.27)
				)
			)
		)
		(property "Value" "SCD1U50V3KX-GP"
			(at 0 -2.8194 90)
			(unlocked yes)
			(layer "F.Fab")
			(hide yes)
			(effects
				(font
					(size 1.016 1.016)
					(thickness 0.1524)
				)
			)
		)
		(property "Device Type" "C603H36"
			(at 0 -4.3434 90)
			(unlocked yes)
			(layer "F.Fab")
			(hide yes)
			(effects
				(font
					(size 1.016 1.016)
					(thickness 0.1524)
				)
			)
		)
		(duplicate_pad_numbers_are_jumpers no)
		(fp_line
			(start 0.508 0)
			(end -0.508 0)
			(stroke
				(width 0.2032)
				(type default)
			)
			(layer "F.SilkS")
		)
		(fp_rect
			(start -0.5842 1.3335)
			(end 0.5842 -1.3335)
			(stroke
				(width 0)
				(type default)
			)
			(fill no)
			(layer "F.CrtYd")
		)
		(fp_rect
			(start -0.5842 1.3335)
			(end 0.5842 -1.3335)
			(stroke
				(width 0)
				(type default)
			)
			(fill no)
			(layer "F.Fab")
		)
		(pad "1" smd custom
			(at 0 -0.762 90)
			(size 0.2159 0.2159)
			(layers "F.Cu" "F.Mask" "F.Paste")
			(net "P1V5_E_SW")
			(options
				(clearance outline)
				(anchor circle)
			)
			(primitives
				(gr_poly
					(pts
						(arc
							(start -0.3302 -0.4318)
							(mid -0.402042 -0.402042)
							(end -0.4318 -0.3302)
						)
						(arc
							(start -0.4318 0.3302)
							(mid -0.402042 0.402042)
							(end -0.3302 0.4318)
						)
						(arc
							(start 0.3302 0.4318)
							(mid 0.402042 0.402042)
							(end 0.4318 0.3302)
						)
						(arc
							(start 0.4318 -0.3302)
							(mid 0.402042 -0.402042)
							(end 0.3302 -0.4318)
						)
					)
					(width 0)
					(fill yes)
				)
			)
		)
		(pad "2" smd custom
			(at 0 0.762 90)
			(size 0.2159 0.2159)
			(layers "F.Cu" "F.Mask" "F.Paste")
			(net "P1V5_E_VBST_RR")
			(options
				(clearance outline)
				(anchor circle)
			)
			(primitives
				(gr_poly
					(pts
						(arc
							(start -0.3302 -0.4318)
							(mid -0.402042 -0.402042)
							(end -0.4318 -0.3302)
						)
						(arc
							(start -0.4318 0.3302)
							(mid -0.402042 0.402042)
							(end -0.3302 0.4318)
						)
						(arc
							(start 0.3302 0.4318)
							(mid 0.402042 0.402042)
							(end 0.4318 0.3302)
						)
						(arc
							(start 0.4318 -0.3302)
							(mid 0.402042 -0.402042)
							(end 0.3302 -0.4318)
						)
					)
					(width 0)
					(fill yes)
				)
			)
		)
	)
	(footprint ""
		(layer "F.Cu")
		(at 320.9544 -212.1154 -90)
		(property "Reference" "R563"
			(at 0 0 270)
			(layer "F.SilkS")
			(hide yes)
			(effects
				(font
					(size 1.27 1.27)
				)
			)
		)
		(property "Value" "10KR2F-2-GP"
			(at 0.064008 -3.993896 270)
			(unlocked yes)
			(layer "F.Fab")
			(hide yes)
			(effects
				(font
					(size 1.016 1.016)
					(thickness 0.1524)
				)
			)
		)
		(property "Device Type" "R402H16"
			(at 0.064008 -5.517896 270)
			(unlocked yes)
			(layer "F.Fab")
			(hide yes)
			(effects
				(font
					(size 1.016 1.016)
					(thickness 0.1524)
				)
			)
		)
		(duplicate_pad_numbers_are_jumpers no)
		(fp_line
			(start -0.508 -0.9398)
			(end -0.508 0.9398)
			(stroke
				(width 0.1524)
				(type default)
			)
			(layer "F.SilkS")
		)
		(fp_line
			(start 0.508 -0.9398)
			(end -0.508 -0.9398)
			(stroke
				(width 0.1524)
				(type default)
			)
			(layer "F.SilkS")
		)
		(fp_rect
			(start -0.508 0.9398)
			(end 0.508 -0.9398)
			(stroke
				(width 0)
				(type default)
			)
			(fill no)
			(layer "F.CrtYd")
		)
		(fp_rect
			(start -0.508 0.9398)
			(end 0.508 -0.9398)
			(stroke
				(width 0)
				(type default)
			)
			(fill no)
			(layer "F.Fab")
		)
		(pad "1" smd custom
			(at 0 -0.4445 270)
			(size 0.1397 0.1397)
			(layers "F.Cu" "F.Mask" "F.Paste")
			(net "P3V3_STBY")
			(options
				(clearance outline)
				(anchor circle)
			)
			(primitives
				(gr_poly
					(pts
						(arc
							(start -0.1778 -0.2794)
							(mid -0.249642 -0.249642)
							(end -0.2794 -0.1778)
						)
						(arc
							(start -0.2794 0.1778)
							(mid -0.249642 0.249642)
							(end -0.1778 0.2794)
						)
						(arc
							(start 0.1778 0.2794)
							(mid 0.249642 0.249642)
							(end 0.2794 0.1778)
						)
						(arc
							(start 0.2794 -0.1778)
							(mid 0.249642 -0.249642)
							(end 0.1778 -0.2794)
						)
					)
					(width 0)
					(fill yes)
				)
			)
		)
		(pad "2" smd custom
			(at 0 0.4445 270)
			(size 0.1397 0.1397)
			(layers "F.Cu" "F.Mask" "F.Paste")
			(net "BMC_JTAG_L_EN")
			(options
				(clearance outline)
				(anchor circle)
			)
			(primitives
				(gr_poly
					(pts
						(arc
							(start -0.1778 -0.2794)
							(mid -0.249642 -0.249642)
							(end -0.2794 -0.1778)
						)
						(arc
							(start -0.2794 0.1778)
							(mid -0.249642 0.249642)
							(end -0.1778 0.2794)
						)
						(arc
							(start 0.1778 0.2794)
							(mid 0.249642 0.249642)
							(end 0.2794 0.1778)
						)
						(arc
							(start 0.2794 -0.1778)
							(mid 0.249642 -0.249642)
							(end 0.1778 -0.2794)
						)
					)
					(width 0)
					(fill yes)
				)
			)
		)
	)
	(footprint ""
		(layer "F.Cu")
		(at 257.429 -230.378 90)
		(property "Reference" "PR88"
			(at 0 0 90)
			(layer "F.SilkS")
			(hide yes)
			(effects
				(font
					(size 1.27 1.27)
				)
			)
		)
		(property "Value" "0R2J-2-GP"
			(at 0.064008 -3.993896 90)
			(unlocked yes)
			(layer "F.Fab")
			(hide yes)
			(effects
				(font
					(size 1.016 1.016)
					(thickness 0.1524)
				)
			)
		)
		(property "Device Type" "R402H16"
			(at 0.064008 -5.517896 90)
			(unlocked yes)
			(layer "F.Fab")
			(hide yes)
			(effects
				(font
					(size 1.016 1.016)
					(thickness 0.1524)
				)
			)
		)
		(duplicate_pad_numbers_are_jumpers no)
		(fp_line
			(start 0.508 -0.9398)
			(end -0.508 -0.9398)
			(stroke
				(width 0.1524)
				(type default)
			)
			(layer "F.SilkS")
		)
		(fp_line
			(start -0.508 -0.9398)
			(end -0.508 0.9398)
			(stroke
				(width 0.1524)
				(type default)
			)
			(layer "F.SilkS")
		)
		(fp_rect
			(start -0.508 0.9398)
			(end 0.508 -0.9398)
			(stroke
				(width 0)
				(type default)
			)
			(fill no)
			(layer "F.CrtYd")
		)
		(fp_rect
			(start -0.508 0.9398)
			(end 0.508 -0.9398)
			(stroke
				(width 0)
				(type default)
			)
			(fill no)
			(layer "F.Fab")
		)
		(pad "1" smd custom
			(at 0 -0.4445 90)
			(size 0.1397 0.1397)
			(layers "F.Cu" "F.Mask" "F.Paste")
			(net "P1V53_STBY_PG")
			(options
				(clearance outline)
				(anchor circle)
			)
			(primitives
				(gr_poly
					(pts
						(arc
							(start -0.1778 -0.2794)
							(mid -0.249642 -0.249642)
							(end -0.2794 -0.1778)
						)
						(arc
							(start -0.2794 0.1778)
							(mid -0.249642 0.249642)
							(end -0.1778 0.2794)
						)
						(arc
							(start 0.1778 0.2794)
							(mid 0.249642 0.249642)
							(end 0.2794 0.1778)
						)
						(arc
							(start 0.2794 -0.1778)
							(mid 0.249642 -0.249642)
							(end 0.1778 -0.2794)
						)
					)
					(width 0)
					(fill yes)
				)
			)
		)
		(pad "2" smd custom
			(at 0 0.4445 90)
			(size 0.1397 0.1397)
			(layers "F.Cu" "F.Mask" "F.Paste")
			(net "TPS74801_1V26_STBY_EN")
			(options
				(clearance outline)
				(anchor circle)
			)
			(primitives
				(gr_poly
					(pts
						(arc
							(start -0.1778 -0.2794)
							(mid -0.249642 -0.249642)
							(end -0.2794 -0.1778)
						)
						(arc
							(start -0.2794 0.1778)
							(mid -0.249642 0.249642)
							(end -0.1778 0.2794)
						)
						(arc
							(start 0.1778 0.2794)
							(mid 0.249642 0.249642)
							(end 0.2794 0.1778)
						)
						(arc
							(start 0.2794 -0.1778)
							(mid 0.249642 -0.249642)
							(end 0.1778 -0.2794)
						)
					)
					(width 0)
					(fill yes)
				)
			)
		)
	)
	(footprint ""
		(layer "F.Cu")
		(at 278.13 -191.77 180)
		(property "Reference" "C201"
			(at 0 0 180)
			(layer "F.SilkS")
			(hide yes)
			(effects
				(font
					(size 1.27 1.27)
				)
			)
		)
		(property "Value" "SC1U6D3V3KX-2GP"
			(at 0 -2.8194 180)
			(unlocked yes)
			(layer "F.Fab")
			(hide yes)
			(effects
				(font
					(size 1.016 1.016)
					(thickness 0.1524)
				)
			)
		)
		(property "Device Type" "C603H36"
			(at 0 -4.3434 180)
			(unlocked yes)
			(layer "F.Fab")
			(hide yes)
			(effects
				(font
					(size 1.016 1.016)
					(thickness 0.1524)
				)
			)
		)
		(duplicate_pad_numbers_are_jumpers no)
		(fp_line
			(start 0.508 0)
			(end -0.508 0)
			(stroke
				(width 0.2032)
				(type default)
			)
			(layer "F.SilkS")
		)
		(fp_rect
			(start -0.5842 1.3335)
			(end 0.5842 -1.3335)
			(stroke
				(width 0)
				(type default)
			)
			(fill no)
			(layer "F.CrtYd")
		)
		(fp_rect
			(start -0.5842 1.3335)
			(end 0.5842 -1.3335)
			(stroke
				(width 0)
				(type default)
			)
			(fill no)
			(layer "F.Fab")
		)
		(pad "1" smd custom
			(at 0 -0.762 180)
			(size 0.2159 0.2159)
			(layers "F.Cu" "F.Mask" "F.Paste")
			(net "V1PLLAV12")
			(options
				(clearance outline)
				(anchor circle)
			)
			(primitives
				(gr_poly
					(pts
						(arc
							(start -0.3302 -0.4318)
							(mid -0.402042 -0.402042)
							(end -0.4318 -0.3302)
						)
						(arc
							(start -0.4318 0.3302)
							(mid -0.402042 0.402042)
							(end -0.3302 0.4318)
						)
						(arc
							(start 0.3302 0.4318)
							(mid 0.402042 0.402042)
							(end 0.4318 0.3302)
						)
						(arc
							(start 0.4318 -0.3302)
							(mid 0.402042 -0.402042)
							(end 0.3302 -0.4318)
						)
					)
					(width 0)
					(fill yes)
				)
			)
		)
		(pad "2" smd custom
			(at 0 0.762 180)
			(size 0.2159 0.2159)
			(layers "F.Cu" "F.Mask" "F.Paste")
			(net "GND")
			(options
				(clearance outline)
				(anchor circle)
			)
			(primitives
				(gr_poly
					(pts
						(arc
							(start -0.3302 -0.4318)
							(mid -0.402042 -0.402042)
							(end -0.4318 -0.3302)
						)
						(arc
							(start -0.4318 0.3302)
							(mid -0.402042 0.402042)
							(end -0.3302 0.4318)
						)
						(arc
							(start 0.3302 0.4318)
							(mid 0.402042 0.402042)
							(end 0.4318 0.3302)
						)
						(arc
							(start 0.4318 -0.3302)
							(mid 0.402042 -0.402042)
							(end 0.3302 -0.4318)
						)
					)
					(width 0)
					(fill yes)
				)
			)
		)
	)
	(footprint ""
		(layer "F.Cu")
		(at 260.785864 -220.209872 -90)
		(property "Reference" "PR87"
			(at 0 0 270)
			(layer "F.SilkS")
			(hide yes)
			(effects
				(font
					(size 1.27 1.27)
				)
			)
		)
		(property "Value" "4K75R2F-1-GP"
			(at 0.064008 -3.993896 270)
			(unlocked yes)
			(layer "F.Fab")
			(hide yes)
			(effects
				(font
					(size 1.016 1.016)
					(thickness 0.1524)
				)
			)
		)
		(property "Device Type" "R402H16"
			(at 0.064008 -5.517896 270)
			(unlocked yes)
			(layer "F.Fab")
			(hide yes)
			(effects
				(font
					(size 1.016 1.016)
					(thickness 0.1524)
				)
			)
		)
		(duplicate_pad_numbers_are_jumpers no)
		(fp_line
			(start -0.508 -0.9398)
			(end -0.508 0.9398)
			(stroke
				(width 0.1524)
				(type default)
			)
			(layer "F.SilkS")
		)
		(fp_line
			(start 0.508 -0.9398)
			(end -0.508 -0.9398)
			(stroke
				(width 0.1524)
				(type default)
			)
			(layer "F.SilkS")
		)
		(fp_rect
			(start -0.508 0.9398)
			(end 0.508 -0.9398)
			(stroke
				(width 0)
				(type default)
			)
			(fill no)
			(layer "F.CrtYd")
		)
		(fp_rect
			(start -0.508 0.9398)
			(end 0.508 -0.9398)
			(stroke
				(width 0)
				(type default)
			)
			(fill no)
			(layer "F.Fab")
		)
		(pad "1" smd custom
			(at 0 -0.4445 270)
			(size 0.1397 0.1397)
			(layers "F.Cu" "F.Mask" "F.Paste")
			(net "TPS74801_1V26_STBY_FB")
			(options
				(clearance outline)
				(anchor circle)
			)
			(primitives
				(gr_poly
					(pts
						(arc
							(start -0.1778 -0.2794)
							(mid -0.249642 -0.249642)
							(end -0.2794 -0.1778)
						)
						(arc
							(start -0.2794 0.1778)
							(mid -0.249642 0.249642)
							(end -0.1778 0.2794)
						)
						(arc
							(start 0.1778 0.2794)
							(mid 0.249642 0.249642)
							(end 0.2794 0.1778)
						)
						(arc
							(start 0.2794 -0.1778)
							(mid 0.249642 -0.249642)
							(end 0.1778 -0.2794)
						)
					)
					(width 0)
					(fill yes)
				)
			)
		)
		(pad "2" smd custom
			(at 0 0.4445 270)
			(size 0.1397 0.1397)
			(layers "F.Cu" "F.Mask" "F.Paste")
			(net "GND")
			(options
				(clearance outline)
				(anchor circle)
			)
			(primitives
				(gr_poly
					(pts
						(arc
							(start -0.1778 -0.2794)
							(mid -0.249642 -0.249642)
							(end -0.2794 -0.1778)
						)
						(arc
							(start -0.2794 0.1778)
							(mid -0.249642 0.249642)
							(end -0.1778 0.2794)
						)
						(arc
							(start 0.1778 0.2794)
							(mid 0.249642 0.249642)
							(end 0.2794 0.1778)
						)
						(arc
							(start 0.2794 -0.1778)
							(mid 0.249642 -0.249642)
							(end 0.1778 -0.2794)
						)
					)
					(width 0)
					(fill yes)
				)
			)
		)
	)
	(footprint ""
		(layer "F.Cu")
		(at 303.320958 -62.865 -90)
		(property "Reference" "R215"
			(at 0 0 270)
			(layer "F.SilkS")
			(hide yes)
			(effects
				(font
					(size 1.27 1.27)
				)
			)
		)
		(property "Value" "0R2J-2-GP"
			(at 0.064008 -3.993896 270)
			(unlocked yes)
			(layer "F.Fab")
			(hide yes)
			(effects
				(font
					(size 1.016 1.016)
					(thickness 0.1524)
				)
			)
		)
		(property "Device Type" "R402H16"
			(at 0.064008 -5.517896 270)
			(unlocked yes)
			(layer "F.Fab")
			(hide yes)
			(effects
				(font
					(size 1.016 1.016)
					(thickness 0.1524)
				)
			)
		)
		(duplicate_pad_numbers_are_jumpers no)
		(fp_line
			(start -0.508 -0.9398)
			(end -0.508 0.9398)
			(stroke
				(width 0.1524)
				(type default)
			)
			(layer "F.SilkS")
		)
		(fp_line
			(start 0.508 -0.9398)
			(end -0.508 -0.9398)
			(stroke
				(width 0.1524)
				(type default)
			)
			(layer "F.SilkS")
		)
		(fp_rect
			(start -0.508 0.9398)
			(end 0.508 -0.9398)
			(stroke
				(width 0)
				(type default)
			)
			(fill no)
			(layer "F.CrtYd")
		)
		(fp_rect
			(start -0.508 0.9398)
			(end 0.508 -0.9398)
			(stroke
				(width 0)
				(type default)
			)
			(fill no)
			(layer "F.Fab")
		)
		(pad "1" smd custom
			(at 0 -0.4445 270)
			(size 0.1397 0.1397)
			(layers "F.Cu" "F.Mask" "F.Paste")
			(net "NCSI_10G_RX_ER_R")
			(options
				(clearance outline)
				(anchor circle)
			)
			(primitives
				(gr_poly
					(pts
						(arc
							(start -0.1778 -0.2794)
							(mid -0.249642 -0.249642)
							(end -0.2794 -0.1778)
						)
						(arc
							(start -0.2794 0.1778)
							(mid -0.249642 0.249642)
							(end -0.1778 0.2794)
						)
						(arc
							(start 0.1778 0.2794)
							(mid 0.249642 0.249642)
							(end 0.2794 0.1778)
						)
						(arc
							(start 0.2794 -0.1778)
							(mid 0.249642 -0.249642)
							(end 0.1778 -0.2794)
						)
					)
					(width 0)
					(fill yes)
				)
			)
		)
		(pad "2" smd custom
			(at 0 0.4445 270)
			(size 0.1397 0.1397)
			(layers "F.Cu" "F.Mask" "F.Paste")
			(net "NCSI_10G_RX_ER")
			(options
				(clearance outline)
				(anchor circle)
			)
			(primitives
				(gr_poly
					(pts
						(arc
							(start -0.1778 -0.2794)
							(mid -0.249642 -0.249642)
							(end -0.2794 -0.1778)
						)
						(arc
							(start -0.2794 0.1778)
							(mid -0.249642 0.249642)
							(end -0.1778 0.2794)
						)
						(arc
							(start 0.1778 0.2794)
							(mid 0.249642 0.249642)
							(end 0.2794 0.1778)
						)
						(arc
							(start 0.2794 -0.1778)
							(mid 0.249642 -0.249642)
							(end 0.1778 -0.2794)
						)
					)
					(width 0)
					(fill yes)
				)
			)
		)
	)
)
